(kicad_pcb
	(version 20260206)
	(generator "pcbnew")
	(generator_version "10.0")
	(general
		(thickness 1.6)
		(legacy_teardrops no)
	)
	(paper "A4")
	(title_block
		(title "fcb — Lightning_FCB_BRD.brd")
		(comment 1 "Lightning (Wiwynn / Facebook NVMe JBOF) / footprints 143-150 of 495")
	)
	(layers
		(0 "F.Cu" signal "TOP")
		(4 "In1.Cu" signal "L2GND")
		(6 "In2.Cu" signal "L3VCC")
		(2 "B.Cu" signal "BOTTOM")
		(9 "F.Adhes" user "F.Adhesive")
		(11 "B.Adhes" user "B.Adhesive")
		(13 "F.Paste" user "Package Geometry/Pastemask Top")
		(15 "B.Paste" user "Package Geometry/Pastemask Bottom")
		(5 "F.SilkS" user "Ref Des/Silkscreen Top")
		(7 "B.SilkS" user "Ref Des/Silkscreen Bottom")
		(1 "F.Mask" user "Board Geometry/Soldermask Top")
		(3 "B.Mask" user "Board Geometry/Soldermask Bottom")
		(17 "Dwgs.User" user "User.Drawings")
		(19 "Cmts.User" user "User.Comments")
		(21 "Eco1.User" user "User.Eco1")
		(23 "Eco2.User" user "User.Eco2")
		(25 "Edge.Cuts" user "Board Geometry/Outline")
		(27 "Margin" user)
		(31 "F.CrtYd" user "Package Geometry/Place Bound Top")
		(29 "B.CrtYd" user "Package Geometry/Place Bound Bottom")
		(35 "F.Fab" user "Ref Des/Assembly Top")
		(33 "B.Fab" user "Ref Des/Assembly Bottom")
	)
	(footprint ""
		(layer "F.Cu")
		(at 47.0154 -419.7858 90)
		(property "Reference" "C26"
			(at 0 0 90)
			(layer "F.SilkS")
			(hide yes)
			(effects
				(font
					(size 1.27 1.27)
				)
			)
		)
		(property "Value" "SC1U25V3KX-1-GP"
			(at 0 -2.8194 90)
			(unlocked yes)
			(layer "F.Fab")
			(hide yes)
			(effects
				(font
					(size 1.016 1.016)
					(thickness 0.1524)
				)
			)
		)
		(property "Device Type" "C603H36"
			(at 0 -4.3434 90)
			(unlocked yes)
			(layer "F.Fab")
			(hide yes)
			(effects
				(font
					(size 1.016 1.016)
					(thickness 0.1524)
				)
			)
		)
		(duplicate_pad_numbers_are_jumpers no)
		(fp_line
			(start 0.508 0)
			(end -0.508 0)
			(stroke
				(width 0.2032)
				(type default)
			)
			(layer "F.SilkS")
		)
		(fp_rect
			(start -0.5842 1.3335)
			(end 0.5842 -1.3335)
			(stroke
				(width 0)
				(type default)
			)
			(fill no)
			(layer "F.CrtYd")
		)
		(fp_rect
			(start -0.5842 1.3335)
			(end 0.5842 -1.3335)
			(stroke
				(width 0)
				(type default)
			)
			(fill no)
			(layer "F.Fab")
		)
		(pad "1" smd custom
			(at 0 -0.762 90)
			(size 0.2159 0.2159)
			(layers "F.Cu" "F.Mask" "F.Paste")
			(net "P12V_AUX")
			(options
				(clearance outline)
				(anchor circle)
			)
			(primitives
				(gr_poly
					(pts
						(arc
							(start -0.3302 -0.4318)
							(mid -0.402042 -0.402042)
							(end -0.4318 -0.3302)
						)
						(arc
							(start -0.4318 0.3302)
							(mid -0.402042 0.402042)
							(end -0.3302 0.4318)
						)
						(arc
							(start 0.3302 0.4318)
							(mid 0.402042 0.402042)
							(end 0.4318 0.3302)
						)
						(arc
							(start 0.4318 -0.3302)
							(mid 0.402042 -0.402042)
							(end 0.3302 -0.4318)
						)
					)
					(width 0)
					(fill yes)
				)
			)
		)
		(pad "2" smd custom
			(at 0 0.762 90)
			(size 0.2159 0.2159)
			(layers "F.Cu" "F.Mask" "F.Paste")
			(net "GND")
			(options
				(clearance outline)
				(anchor circle)
			)
			(primitives
				(gr_poly
					(pts
						(arc
							(start -0.3302 -0.4318)
							(mid -0.402042 -0.402042)
							(end -0.4318 -0.3302)
						)
						(arc
							(start -0.4318 0.3302)
							(mid -0.402042 0.402042)
							(end -0.3302 0.4318)
						)
						(arc
							(start 0.3302 0.4318)
							(mid 0.402042 0.402042)
							(end 0.4318 0.3302)
						)
						(arc
							(start 0.4318 -0.3302)
							(mid 0.402042 -0.402042)
							(end 0.3302 -0.4318)
						)
					)
					(width 0)
					(fill yes)
				)
			)
		)
	)
	(footprint ""
		(layer "F.Cu")
		(at 24.1808 -168.656)
		(property "Reference" "R20"
			(at 0 0 0)
			(layer "F.SilkS")
			(hide yes)
			(effects
				(font
					(size 1.27 1.27)
				)
			)
		)
		(property "Value" "4K7R2F-GP"
			(at 0.064008 -3.993896 0)
			(unlocked yes)
			(layer "F.Fab")
			(hide yes)
			(effects
				(font
					(size 1.016 1.016)
					(thickness 0.1524)
				)
			)
		)
		(property "Device Type" "R402H16"
			(at 0.064008 -5.517896 0)
			(unlocked yes)
			(layer "F.Fab")
			(hide yes)
			(effects
				(font
					(size 1.016 1.016)
					(thickness 0.1524)
				)
			)
		)
		(duplicate_pad_numbers_are_jumpers no)
		(fp_line
			(start -0.508 -0.9398)
			(end -0.508 0.9398)
			(stroke
				(width 0.1524)
				(type default)
			)
			(layer "F.SilkS")
		)
		(fp_line
			(start 0.508 -0.9398)
			(end -0.508 -0.9398)
			(stroke
				(width 0.1524)
				(type default)
			)
			(layer "F.SilkS")
		)
		(fp_rect
			(start -0.508 0.9398)
			(end 0.508 -0.9398)
			(stroke
				(width 0)
				(type default)
			)
			(fill no)
			(layer "F.CrtYd")
		)
		(fp_rect
			(start -0.508 0.9398)
			(end 0.508 -0.9398)
			(stroke
				(width 0)
				(type default)
			)
			(fill no)
			(layer "F.Fab")
		)
		(pad "1" smd custom
			(at 0 -0.4445)
			(size 0.1397 0.1397)
			(layers "F.Cu" "F.Mask" "F.Paste")
			(net "P3V3")
			(options
				(clearance outline)
				(anchor circle)
			)
			(primitives
				(gr_poly
					(pts
						(arc
							(start -0.1778 -0.2794)
							(mid -0.249642 -0.249642)
							(end -0.2794 -0.1778)
						)
						(arc
							(start -0.2794 0.1778)
							(mid -0.249642 0.249642)
							(end -0.1778 0.2794)
						)
						(arc
							(start 0.1778 0.2794)
							(mid 0.249642 0.249642)
							(end 0.2794 0.1778)
						)
						(arc
							(start 0.2794 -0.1778)
							(mid 0.249642 -0.249642)
							(end 0.1778 -0.2794)
						)
					)
					(width 0)
					(fill yes)
				)
			)
		)
		(pad "2" smd custom
			(at 0 0.4445)
			(size 0.1397 0.1397)
			(layers "F.Cu" "F.Mask" "F.Paste")
			(net "PWM_BUFFER_IN_FAN5_FAN6")
			(options
				(clearance outline)
				(anchor circle)
			)
			(primitives
				(gr_poly
					(pts
						(arc
							(start -0.1778 -0.2794)
							(mid -0.249642 -0.249642)
							(end -0.2794 -0.1778)
						)
						(arc
							(start -0.2794 0.1778)
							(mid -0.249642 0.249642)
							(end -0.1778 0.2794)
						)
						(arc
							(start 0.1778 0.2794)
							(mid 0.249642 0.249642)
							(end 0.2794 0.1778)
						)
						(arc
							(start 0.2794 -0.1778)
							(mid 0.249642 -0.249642)
							(end 0.1778 -0.2794)
						)
					)
					(width 0)
					(fill yes)
				)
			)
		)
	)
	(footprint ""
		(layer "F.Cu")
		(at 37.846508 -282.993338)
		(property "Reference" "C47"
			(at 0 0 0)
			(layer "F.SilkS")
			(hide yes)
			(effects
				(font
					(size 1.27 1.27)
				)
			)
		)
		(property "Value" "SCD1U50V3KX-GP"
			(at 0 -2.8194 0)
			(unlocked yes)
			(layer "F.Fab")
			(hide yes)
			(effects
				(font
					(size 1.016 1.016)
					(thickness 0.1524)
				)
			)
		)
		(property "Device Type" "C603H36"
			(at 0 -4.3434 0)
			(unlocked yes)
			(layer "F.Fab")
			(hide yes)
			(effects
				(font
					(size 1.016 1.016)
					(thickness 0.1524)
				)
			)
		)
		(duplicate_pad_numbers_are_jumpers no)
		(fp_line
			(start 0.508 0)
			(end -0.508 0)
			(stroke
				(width 0.2032)
				(type default)
			)
			(layer "F.SilkS")
		)
		(fp_rect
			(start -0.5842 1.3335)
			(end 0.5842 -1.3335)
			(stroke
				(width 0)
				(type default)
			)
			(fill no)
			(layer "F.CrtYd")
		)
		(fp_rect
			(start -0.5842 1.3335)
			(end 0.5842 -1.3335)
			(stroke
				(width 0)
				(type default)
			)
			(fill no)
			(layer "F.Fab")
		)
		(pad "1" smd custom
			(at 0 -0.762)
			(size 0.2159 0.2159)
			(layers "F.Cu" "F.Mask" "F.Paste")
			(net "P12V")
			(options
				(clearance outline)
				(anchor circle)
			)
			(primitives
				(gr_poly
					(pts
						(arc
							(start -0.3302 -0.4318)
							(mid -0.402042 -0.402042)
							(end -0.4318 -0.3302)
						)
						(arc
							(start -0.4318 0.3302)
							(mid -0.402042 0.402042)
							(end -0.3302 0.4318)
						)
						(arc
							(start 0.3302 0.4318)
							(mid 0.402042 0.402042)
							(end 0.4318 0.3302)
						)
						(arc
							(start 0.4318 -0.3302)
							(mid 0.402042 -0.402042)
							(end 0.3302 -0.4318)
						)
					)
					(width 0)
					(fill yes)
				)
			)
		)
		(pad "2" smd custom
			(at 0 0.762)
			(size 0.2159 0.2159)
			(layers "F.Cu" "F.Mask" "F.Paste")
			(net "GND")
			(options
				(clearance outline)
				(anchor circle)
			)
			(primitives
				(gr_poly
					(pts
						(arc
							(start -0.3302 -0.4318)
							(mid -0.402042 -0.402042)
							(end -0.4318 -0.3302)
						)
						(arc
							(start -0.4318 0.3302)
							(mid -0.402042 0.402042)
							(end -0.3302 0.4318)
						)
						(arc
							(start 0.3302 0.4318)
							(mid 0.402042 0.402042)
							(end 0.4318 0.3302)
						)
						(arc
							(start 0.4318 -0.3302)
							(mid 0.402042 -0.402042)
							(end 0.3302 -0.4318)
						)
					)
					(width 0)
					(fill yes)
				)
			)
		)
	)
	(footprint ""
		(layer "F.Cu")
		(at 31.96209 -150.781766 180)
		(property "Reference" "TP6"
			(at 0 0 180)
			(layer "F.SilkS")
			(hide yes)
			(effects
				(font
					(size 1.27 1.27)
				)
			)
		)
		(property "Value" "TPAD32-GP"
			(at 0 -3.166364 180)
			(unlocked yes)
			(layer "F.Fab")
			(hide yes)
			(effects
				(font
					(size 1.016 1.016)
					(thickness 0.1524)
				)
			)
		)
		(property "Device Type" "TPAD32"
			(at 0 -4.690618 180)
			(unlocked yes)
			(layer "F.Fab")
			(hide yes)
			(effects
				(font
					(size 1.016 1.016)
					(thickness 0.1524)
				)
			)
		)
		(duplicate_pad_numbers_are_jumpers no)
		(fp_poly
			(pts
				(arc
					(start 0.7112 0)
					(mid -0.7112 0)
					(end 0.7112 0)
				)
			)
			(stroke
				(width 0)
				(type default)
			)
			(fill no)
			(layer "F.CrtYd")
		)
		(fp_poly
			(pts
				(arc
					(start 0.7112 0)
					(mid -0.7112 0)
					(end 0.7112 0)
				)
			)
			(stroke
				(width 0)
				(type default)
			)
			(fill no)
			(layer "F.Fab")
		)
		(pad "1" smd circle
			(at 0 0 180)
			(size 0.8128 0.8128)
			(layers "F.Cu" "F.Mask" "F.Paste")
			(net "NCT7904_VSEN8")
		)
	)
	(footprint ""
		(layer "F.Cu")
		(at 24.257 -371.475 180)
		(property "Reference" "PR36"
			(at 0 0 180)
			(layer "F.SilkS")
			(hide yes)
			(effects
				(font
					(size 1.27 1.27)
				)
			)
		)
		(property "Value" "4K02R2F-GP"
			(at 0.064008 -3.993896 180)
			(unlocked yes)
			(layer "F.Fab")
			(hide yes)
			(effects
				(font
					(size 1.016 1.016)
					(thickness 0.1524)
				)
			)
		)
		(property "Device Type" "R402H16"
			(at 0.064008 -5.517896 180)
			(unlocked yes)
			(layer "F.Fab")
			(hide yes)
			(effects
				(font
					(size 1.016 1.016)
					(thickness 0.1524)
				)
			)
		)
		(duplicate_pad_numbers_are_jumpers no)
		(fp_line
			(start 0.508 -0.9398)
			(end -0.508 -0.9398)
			(stroke
				(width 0.1524)
				(type default)
			)
			(layer "F.SilkS")
		)
		(fp_line
			(start -0.508 -0.9398)
			(end -0.508 0.9398)
			(stroke
				(width 0.1524)
				(type default)
			)
			(layer "F.SilkS")
		)
		(fp_rect
			(start -0.508 0.9398)
			(end 0.508 -0.9398)
			(stroke
				(width 0)
				(type default)
			)
			(fill no)
			(layer "F.CrtYd")
		)
		(fp_rect
			(start -0.508 0.9398)
			(end 0.508 -0.9398)
			(stroke
				(width 0)
				(type default)
			)
			(fill no)
			(layer "F.Fab")
		)
		(pad "1" smd custom
			(at 0 -0.4445 180)
			(size 0.1397 0.1397)
			(layers "F.Cu" "F.Mask" "F.Paste")
			(net "ADM1276_OV")
			(options
				(clearance outline)
				(anchor circle)
			)
			(primitives
				(gr_poly
					(pts
						(arc
							(start -0.1778 -0.2794)
							(mid -0.249642 -0.249642)
							(end -0.2794 -0.1778)
						)
						(arc
							(start -0.2794 0.1778)
							(mid -0.249642 0.249642)
							(end -0.1778 0.2794)
						)
						(arc
							(start 0.1778 0.2794)
							(mid 0.249642 0.249642)
							(end 0.2794 0.1778)
						)
						(arc
							(start 0.2794 -0.1778)
							(mid 0.249642 -0.249642)
							(end 0.1778 -0.2794)
						)
					)
					(width 0)
					(fill yes)
				)
			)
		)
		(pad "2" smd custom
			(at 0 0.4445 180)
			(size 0.1397 0.1397)
			(layers "F.Cu" "F.Mask" "F.Paste")
			(net "GND")
			(options
				(clearance outline)
				(anchor circle)
			)
			(primitives
				(gr_poly
					(pts
						(arc
							(start -0.1778 -0.2794)
							(mid -0.249642 -0.249642)
							(end -0.2794 -0.1778)
						)
						(arc
							(start -0.2794 0.1778)
							(mid -0.249642 0.249642)
							(end -0.1778 0.2794)
						)
						(arc
							(start 0.1778 0.2794)
							(mid 0.249642 0.249642)
							(end 0.2794 0.1778)
						)
						(arc
							(start 0.2794 -0.1778)
							(mid 0.249642 -0.249642)
							(end 0.1778 -0.2794)
						)
					)
					(width 0)
					(fill yes)
				)
			)
		)
	)
	(footprint ""
		(layer "F.Cu")
		(at 38.692074 -363.062774 180)
		(property "Reference" "PR40"
			(at 0 0 180)
			(layer "F.SilkS")
			(hide yes)
			(effects
				(font
					(size 1.27 1.27)
				)
			)
		)
		(property "Value" "54K9R2F-L-GP"
			(at 0.064008 -3.993896 180)
			(unlocked yes)
			(layer "F.Fab")
			(hide yes)
			(effects
				(font
					(size 1.016 1.016)
					(thickness 0.1524)
				)
			)
		)
		(property "Device Type" "R402H16"
			(at 0.064008 -5.517896 180)
			(unlocked yes)
			(layer "F.Fab")
			(hide yes)
			(effects
				(font
					(size 1.016 1.016)
					(thickness 0.1524)
				)
			)
		)
		(duplicate_pad_numbers_are_jumpers no)
		(fp_line
			(start 0.508 -0.9398)
			(end -0.508 -0.9398)
			(stroke
				(width 0.1524)
				(type default)
			)
			(layer "F.SilkS")
		)
		(fp_line
			(start -0.508 -0.9398)
			(end -0.508 0.9398)
			(stroke
				(width 0.1524)
				(type default)
			)
			(layer "F.SilkS")
		)
		(fp_rect
			(start -0.508 0.9398)
			(end 0.508 -0.9398)
			(stroke
				(width 0)
				(type default)
			)
			(fill no)
			(layer "F.CrtYd")
		)
		(fp_rect
			(start -0.508 0.9398)
			(end 0.508 -0.9398)
			(stroke
				(width 0)
				(type default)
			)
			(fill no)
			(layer "F.Fab")
		)
		(pad "1" smd custom
			(at 0 -0.4445 180)
			(size 0.1397 0.1397)
			(layers "F.Cu" "F.Mask" "F.Paste")
			(net "P12V_AUX")
			(options
				(clearance outline)
				(anchor circle)
			)
			(primitives
				(gr_poly
					(pts
						(arc
							(start -0.1778 -0.2794)
							(mid -0.249642 -0.249642)
							(end -0.2794 -0.1778)
						)
						(arc
							(start -0.2794 0.1778)
							(mid -0.249642 0.249642)
							(end -0.1778 0.2794)
						)
						(arc
							(start 0.1778 0.2794)
							(mid 0.249642 0.249642)
							(end 0.2794 0.1778)
						)
						(arc
							(start 0.2794 -0.1778)
							(mid 0.249642 -0.249642)
							(end 0.1778 -0.2794)
						)
					)
					(width 0)
					(fill yes)
				)
			)
		)
		(pad "2" smd custom
			(at 0 0.4445 180)
			(size 0.1397 0.1397)
			(layers "F.Cu" "F.Mask" "F.Paste")
			(net "TEMP_ALM#_REVERSE")
			(options
				(clearance outline)
				(anchor circle)
			)
			(primitives
				(gr_poly
					(pts
						(arc
							(start -0.1778 -0.2794)
							(mid -0.249642 -0.249642)
							(end -0.2794 -0.1778)
						)
						(arc
							(start -0.2794 0.1778)
							(mid -0.249642 0.249642)
							(end -0.1778 0.2794)
						)
						(arc
							(start 0.1778 0.2794)
							(mid 0.249642 0.249642)
							(end 0.2794 0.1778)
						)
						(arc
							(start 0.2794 -0.1778)
							(mid 0.249642 -0.249642)
							(end 0.1778 -0.2794)
						)
					)
					(width 0)
					(fill yes)
				)
			)
		)
	)
	(footprint ""
		(layer "F.Cu")
		(at 19.1008 -187.8838)
		(property "Reference" "C37"
			(at 0 0 0)
			(layer "F.SilkS")
			(hide yes)
			(effects
				(font
					(size 1.27 1.27)
				)
			)
		)
		(property "Value" "SCD1U16V2KX-3GP"
			(at 1.1811 -2.7051 0)
			(unlocked yes)
			(layer "F.Fab")
			(hide yes)
			(effects
				(font
					(size 1.016 1.016)
					(thickness 0.1524)
				)
			)
		)
		(property "Device Type" "C402H22"
			(at 1.1811 -4.2291 0)
			(unlocked yes)
			(layer "F.Fab")
			(hide yes)
			(effects
				(font
					(size 1.016 1.016)
					(thickness 0.1524)
				)
			)
		)
		(duplicate_pad_numbers_are_jumpers no)
		(fp_rect
			(start -0.4318 0.9525)
			(end 0.4318 -0.9525)
			(stroke
				(width 0)
				(type default)
			)
			(fill no)
			(layer "F.CrtYd")
		)
		(fp_rect
			(start -0.4318 0.9525)
			(end 0.4318 -0.9525)
			(stroke
				(width 0)
				(type default)
			)
			(fill no)
			(layer "F.Fab")
		)
		(pad "1" smd custom
			(at 0 -0.4445)
			(size 0.1524 0.1524)
			(layers "F.Cu" "F.Mask" "F.Paste")
			(net "FAN_TACH8")
			(options
				(clearance outline)
				(anchor circle)
			)
			(primitives
				(gr_poly
					(pts
						(arc
							(start 0.3048 -0.2032)
							(mid 0.275042 -0.275042)
							(end 0.2032 -0.3048)
						)
						(arc
							(start -0.2032 -0.3048)
							(mid -0.275042 -0.275042)
							(end -0.3048 -0.2032)
						)
						(arc
							(start -0.3048 0.2032)
							(mid -0.275042 0.275042)
							(end -0.2032 0.3048)
						)
						(arc
							(start 0.2032 0.3048)
							(mid 0.275042 0.275042)
							(end 0.3048 0.2032)
						)
					)
					(width 0)
					(fill yes)
				)
			)
		)
		(pad "2" smd custom
			(at 0 0.4445)
			(size 0.1524 0.1524)
			(layers "F.Cu" "F.Mask" "F.Paste")
			(net "GND")
			(options
				(clearance outline)
				(anchor circle)
			)
			(primitives
				(gr_poly
					(pts
						(arc
							(start 0.3048 -0.2032)
							(mid 0.275042 -0.275042)
							(end 0.2032 -0.3048)
						)
						(arc
							(start -0.2032 -0.3048)
							(mid -0.275042 -0.275042)
							(end -0.3048 -0.2032)
						)
						(arc
							(start -0.3048 0.2032)
							(mid -0.275042 0.275042)
							(end -0.2032 0.3048)
						)
						(arc
							(start 0.2032 0.3048)
							(mid 0.275042 0.275042)
							(end 0.3048 0.2032)
						)
					)
					(width 0)
					(fill yes)
				)
			)
		)
	)
	(footprint ""
		(layer "F.Cu")
		(at 15.5702 -259.2324 -90)
		(property "Reference" "R88"
			(at 0 0 270)
			(layer "F.SilkS")
			(hide yes)
			(effects
				(font
					(size 1.27 1.27)
				)
			)
		)
		(property "Value" "10KR2F-2-GP"
			(at 0.064008 -3.993896 270)
			(unlocked yes)
			(layer "F.Fab")
			(hide yes)
			(effects
				(font
					(size 1.016 1.016)
					(thickness 0.1524)
				)
			)
		)
		(property "Device Type" "R402H16"
			(at 0.064008 -5.517896 270)
			(unlocked yes)
			(layer "F.Fab")
			(hide yes)
			(effects
				(font
					(size 1.016 1.016)
					(thickness 0.1524)
				)
			)
		)
		(duplicate_pad_numbers_are_jumpers no)
		(fp_line
			(start -0.508 -0.9398)
			(end -0.508 0.9398)
			(stroke
				(width 0.1524)
				(type default)
			)
			(layer "F.SilkS")
		)
		(fp_line
			(start 0.508 -0.9398)
			(end -0.508 -0.9398)
			(stroke
				(width 0.1524)
				(type default)
			)
			(layer "F.SilkS")
		)
		(fp_rect
			(start -0.508 0.9398)
			(end 0.508 -0.9398)
			(stroke
				(width 0)
				(type default)
			)
			(fill no)
			(layer "F.CrtYd")
		)
		(fp_rect
			(start -0.508 0.9398)
			(end 0.508 -0.9398)
			(stroke
				(width 0)
				(type default)
			)
			(fill no)
			(layer "F.Fab")
		)
		(pad "1" smd custom
			(at 0 -0.4445 270)
			(size 0.1397 0.1397)
			(layers "F.Cu" "F.Mask" "F.Paste")
			(net "FANIN_6")
			(options
				(clearance outline)
				(anchor circle)
			)
			(primitives
				(gr_poly
					(pts
						(arc
							(start -0.1778 -0.2794)
							(mid -0.249642 -0.249642)
							(end -0.2794 -0.1778)
						)
						(arc
							(start -0.2794 0.1778)
							(mid -0.249642 0.249642)
							(end -0.1778 0.2794)
						)
						(arc
							(start 0.1778 0.2794)
							(mid 0.249642 0.249642)
							(end 0.2794 0.1778)
						)
						(arc
							(start 0.2794 -0.1778)
							(mid 0.249642 -0.249642)
							(end 0.1778 -0.2794)
						)
					)
					(width 0)
					(fill yes)
				)
			)
		)
		(pad "2" smd custom
			(at 0 0.4445 270)
			(size 0.1397 0.1397)
			(layers "F.Cu" "F.Mask" "F.Paste")
			(net "GND")
			(options
				(clearance outline)
				(anchor circle)
			)
			(primitives
				(gr_poly
					(pts
						(arc
							(start -0.1778 -0.2794)
							(mid -0.249642 -0.249642)
							(end -0.2794 -0.1778)
						)
						(arc
							(start -0.2794 0.1778)
							(mid -0.249642 0.249642)
							(end -0.1778 0.2794)
						)
						(arc
							(start 0.1778 0.2794)
							(mid 0.249642 0.249642)
							(end 0.2794 0.1778)
						)
						(arc
							(start 0.2794 -0.1778)
							(mid 0.249642 -0.249642)
							(end 0.1778 -0.2794)
						)
					)
					(width 0)
					(fill yes)
				)
			)
		)
	)
)
